# SCM (Grand Teton) — schematic parts with pin connectivity, parts 1396–1428 of 1428; source: Cadence DE-HDL packaged netlist (pstxprt.dat, pstxnet.dat, pstchip.dat)

U40  PCA9555PW  IC  pkg SMLF  page 28
  1  \int*\  OUT  = LED_POSTCODE_INT
  2  A1  BI  = LED_POSTCODE_A1
  3  A2  BI  = LED_POSTCODE_A2
  4  P00  BI  = LED_POSTCODE_0_R1
  5  P01  BI  = LED_POSTCODE_1_R1
  6  P02  BI  = LED_POSTCODE_2_R1
  7  P03  BI  = LED_POSTCODE_3_R1
  8  P04  BI  = LED_POSTCODE_4_R1
  9  P05  BI  = LED_POSTCODE_5_R1
  10  P06  BI  = LED_POSTCODE_6_R1
  11  P07  BI  = LED_POSTCODE_7_R1
  12  VSS  POWER  = GND
  13  P10  BI  = FM_DEBUG_RST_BTN_N
  14  P11  BI  = FM_DEBUG_PWR_BTN_N
  15  P12  BI  = PWRGD_SYS_PWROK_R1
  16  P13  BI  = RST_PLTRST_R2_N
  17  P14  BI  = PWRGD_DSW_PWROK_R3
  18  P15  BI  = FM_CPU_MSMI_CATERR_LVT3_R3_N
  19  P16  BI  = FM_SLPS3_GF_R2_N
  20  P17  BI  = FM_UART_SWITCH_N
  21  A0  BI  = LED_POSTCODE_A0
  22  SCL  BI  = SMB_DEBUG_AUX_LVC3_USB_R3_SCL
  23  SDA  BI  = SMB_DEBUG_AUX_LVC3_USB_R3_SDA
  24  VDD  POWER  = P3V3_AUX

U41  RT9059GQW  IC  pkg DFN10_THXE  page 54
  1  VOUT1  OUT  = P1V8_AUX
  2  VOUT2  OUT  = P1V8_AUX
  3  VOUT3  OUT  = P1V8_AUX
  4  ADJ  IN  = U41_ADJ
  5  PGOOD  OUT  = PWRGD_P1V8_AUX_R
  6  EN  IN  = EN_P1V8_R
  7  VIN1  IN  = P3V3_AUX
  8  VIN2  IN  = P3V3_AUX
  9  VIN3  IN  = P3V3_AUX
  10  VDD  IN  = P5V_AUX
  TH  EP  POWER  = GND

U42  MC74VHC1G32DTT1G  IC  pkg SOT23-5_0-95_3X1-5  page 52
  1  IN_B  IN  = PWRGD_P5V_AUX
  2  IN_A  IN  = PWRGD_P1V8_AUX
  3  GND  POWER  = GND
  4  OUT_Y  OUT  = EN_P3V3
  5  VCC  POWER  = P3V3_LDO

U43  TPS3808G18DBVR  TPS3808G01DBVR IC  pkg SOT23-6XD  page 22
  1  \#reset\  OUT  = PWRGD_P1V0_AUX_DELAY_R1
  2  GND  POWER  = GND
  3  \#mr\  IN  = PWRGD_P1V0_AUX_R2
  4  CT  IN  = U43_CT
  5  SENSE  POWER  = P1V0_AUX
  6  VDD  POWER  = P3V3_AUX

U44  SN74LVC1G07DCKR  IC  pkg SC70-5XB  page 25
  1  NC1  TRI  = NC
  2  A  IN  = RST_SPI_FLASH_R_N
  3  GND  POWER  = GND
  4  Y  OCA  = RST_SPI_FLASH_BUF_R3_N
  5  VCC  POWER  = P3V3_AUX

U47  74LVC2G07DW7  74LVC2G07DW-7 IC  pkg SOT363_0-65_2X1-25XC  page 30
  1  \1a\  IN  = UART_BMC_5_TXD_R
  2  GND  POWER  = GND
  3  \2a\  IN  = UART_BMC_5_RXD_BUF1
  4  \2y\  OUT  = UART_BMC_5_RXD_BUF1_R
  5  VCC  POWER  = P3V3_AUX
  6  \1y\  OUT  = UART_BMC_5_TXD_BUF1

U48  BAS70057F  BAS70-05-7-F IC  pkg SOT23_123XB  page 50
  1  B  IN  = P3V_BAT_R
  2  A  IN  = P3V3_AUX
  3  C  BI  = P3V3_RTC_AUX

U49  MC74VHC1G32DTT1G  IC  pkg SOT23-5_0-95_3X1-5  page 54
  1  IN_B  IN  = PWRGD_P5V_AUX
  2  IN_A  IN  = PWRGD_P3V3_RGM_R2
  3  GND  POWER  = GND
  4  OUT_Y  OUT  = EN_P1V8
  5  VCC  POWER  = P3V3_LDO

U50  NC7SB3157  NC7SB3157P6X IC  pkg SMLF  page 31
  1  B1  BI  = UART_BIC_DBG_TX_R
  2  GND  POWER  = GND
  3  B0  BI  = UART_6_BMC_RXD_R
  4  A  BI  = UART_BIC_GF_RXD
  5  VCC  POWER  = P3V3_AUX
  6  S  IN  = FM_BIC_DEBUG_SW_N

U51  NC7SB3157  NC7SB3157P6X IC  pkg SMLF  page 31
  1  B1  BI  = UART_BIC_DBG_RX_R
  2  GND  POWER  = GND
  3  B0  BI  = UART_6_BMC_TXD_R
  4  A  BI  = UART_BIC_GF_TXD
  5  VCC  POWER  = P3V3_AUX
  6  S  IN  = FM_BIC_DEBUG_SW_N

U52  74LVC1G08GW  IC  pkg SM  page 55
  1  B  BI  = PWRGD_P5V_AUX
  2  A  BI  = PWRGD_P3V3_RGM
  3  GND  POWER  = GND
  4  Y  BI  = EN_P1V2_AUX
  5  VCC  POWER  = P3V3_LDO

U53  74LVC1G08GW  IC  pkg SM  page 56
  1  B  BI  = PWRGD_P5V_AUX
  2  A  BI  = PWRGD_P1V2_AUX
  3  GND  POWER  = GND
  4  Y  BI  = EN_P1V0_AUX
  5  VCC  POWER  = P3V3_LDO

U54  74LVC1G74DP  IC  pkg TSSOP8_0-65_3X3  page 25
  1  CP  IN  = FLASH_LATCH_CP
  2  D  IN  = FLASH_LATCH_D
  3  Q_N  OUT  = FLASH_LATCH_Q_N_R
  4  GND  POWER  = GND
  5  Q  OUT  = NC_U54_P1
  6  RD_N  IN  = RD_N
  7  SD_N  IN  = FM_FLASH_LATCH_N
  8  VCC  POWER  = P3V3_AUX

U55  SN74LVC1G14DCKR  IC  pkg SMLF  page 25
  1  NC  TRI  = NC_U55_P1
  2  A  IN  = FLASH_LATCH_Q_N_R2
  3  GND  POWER  = GND
  4  Y  OCA  = FLASH_R_WP_STATUS
  5  VCC  POWER  = P3V3_AUX

U56  AP2205W57  AP2205-W5-7 IC  pkg SOT25-5_0-95_2-96X1-6  page 51
  1  VIN  POWER  = P12V_AUX
  2  GND  POWER  = GND
  3  EN  IN  = P12V_AUX
  4  \adj||nc\  BI  = U56_ADJ_1
  5  VOUT  POWER  = P3V3_LDO

U57  74LVC1G07GW  IC  pkg SOT353_Q  page 50
  1  NC  TRI  = NC_U57_P1
  2  A  IN  = REAR_AC_PWR_BMC_BTN_N
  3  GND  POWER  = GND
  4  Y  OCA  = AC_PWR_BMC_BTN_N
  5  VCC  POWER  = P3V3_AUX

U58  MC74VHC1G32DTT1G  IC  pkg SOT23-5_0-95_3X1-5  page 22
  1  IN_B  IN  = RST_BMC_SELF_HW_R3
  2  IN_A  IN  = RST_BMC_HW_R1
  3  GND  POWER  = GND
  4  OUT_Y  OUT  = RST_BMC_HW_OUT
  5  VCC  POWER  = P3V3_AUX

X1  TP_TDR_4P_FTS  TP_TDR_4P_DIP EMPTY  pkg TH  page 60
  1  S1  BI  = TDR_DIFF_85_TOP_DP
  2  P1  BI  = GND_P1
  3  P2  BI  = GND_P1
  4  S2  BI  = TDR_DIFF_85_TOP_DN

X2  TP_TDR_4P_FTS  TP_TDR_4P_DIP EMPTY  pkg TH  page 60
  1  S1  BI  = TDR_DIFF_85_IN1_DP
  2  P1  BI  = GND_P1
  3  P2  BI  = GND_P1
  4  S2  BI  = TDR_DIFF_85_IN1_DN

X5  TP_TDR_4P_FTS  TP_TDR_4P_DIP EMPTY  pkg TH  page 60
  1  S1  BI  = TDR_DIFF_85_IN4_DP
  2  P1  BI  = GND_P1
  3  P2  BI  = GND_P1
  4  S2  BI  = TDR_DIFF_85_IN4_DN

X6  TP_TDR_4P_FTS  TP_TDR_4P_DIP EMPTY  pkg TH  page 60
  1  S1  BI  = TDR_DIFF_85_BOT_DP
  2  P1  BI  = GND_P1
  3  P2  BI  = GND_P1
  4  S2  BI  = TDR_DIFF_85_BOT_DN

X7  TP_TDR_4P_FTS  TP_TDR_4P_DIP EMPTY  pkg TH  page 60
  1  S1  BI  = TDR_DIFF_85_TOP_DN
  2  P1  BI  = GND_P1
  3  P2  BI  = GND_P1
  4  S2  BI  = TDR_DIFF_85_TOP_DP

X8  TP_TDR_4P_FTS  TP_TDR_4P_DIP EMPTY  pkg TH  page 60
  1  S1  BI  = TDR_DIFF_85_IN1_DN
  2  P1  BI  = GND_P1
  3  P2  BI  = GND_P1
  4  S2  BI  = TDR_DIFF_85_IN1_DP

X11  TP_TDR_4P_FTS  TP_TDR_4P_DIP EMPTY  pkg TH  page 60
  1  S1  BI  = TDR_DIFF_85_IN4_DN
  2  P1  BI  = GND_P1
  3  P2  BI  = GND_P1
  4  S2  BI  = TDR_DIFF_85_IN4_DP

X12  TP_TDR_4P_FTS  TP_TDR_4P_DIP EMPTY  pkg TH  page 60
  1  S1  BI  = TDR_DIFF_85_BOT_DN
  2  P1  BI  = GND_P1
  3  P2  BI  = GND_P1
  4  S2  BI  = TDR_DIFF_85_BOT_DP

X13  TP_TDR_4P_FTS  TP_TDR_4P_DIP EMPTY  pkg TH  page 60
  1  S1  BI  = TDR_DIFF_100_TOP_DP
  2  P1  BI  = GND_P1
  3  P2  BI  = GND_P1
  4  S2  BI  = TDR_DIFF_100_TOP_DN

X14  TP_TDR_4P_FTS  TP_TDR_4P_DIP EMPTY  pkg TH  page 60
  1  S1  BI  = TDR_DIFF_100_IN1_DP
  2  P1  BI  = GND_P1
  3  P2  BI  = GND_P1
  4  S2  BI  = TDR_DIFF_100_IN1_DN

X17  TP_TDR_4P_FTS  TP_TDR_4P_DIP EMPTY  pkg TH  page 60
  1  S1  BI  = TDR_DIFF_100_IN4_DP
  2  P1  BI  = GND_P1
  3  P2  BI  = GND_P1
  4  S2  BI  = TDR_DIFF_100_IN4_DN

X18  TP_TDR_4P_FTS  TP_TDR_4P_DIP EMPTY  pkg TH  page 60
  1  S1  BI  = TDR_DIFF_100_BOT_DP
  2  P1  BI  = GND_P1
  3  P2  BI  = GND_P1
  4  S2  BI  = TDR_DIFF_100_BOT_DN

X19  TP_TDR_4P_FTS  TP_TDR_4P_DIP EMPTY  pkg TH  page 60
  1  S1  BI  = TDR_DIFF_100_TOP_DN
  2  P1  BI  = GND_P1
  3  P2  BI  = GND_P1
  4  S2  BI  = TDR_DIFF_100_TOP_DP

X20  TP_TDR_4P_FTS  TP_TDR_4P_DIP EMPTY  pkg TH  page 60
  1  S1  BI  = TDR_DIFF_100_IN1_DN
  2  P1  BI  = GND_P1
  3  P2  BI  = GND_P1
  4  S2  BI  = TDR_DIFF_100_IN1_DP

X23  TP_TDR_4P_FTS  TP_TDR_4P_DIP EMPTY  pkg TH  page 60
  1  S1  BI  = TDR_DIFF_100_IN4_DN
  2  P1  BI  = GND_P1
  3  P2  BI  = GND_P1
  4  S2  BI  = TDR_DIFF_100_IN4_DP

X24  TP_TDR_4P_FTS  TP_TDR_4P_DIP EMPTY  pkg TH  page 60
  1  S1  BI  = TDR_DIFF_100_BOT_DN
  2  P1  BI  = GND_P1
  3  P2  BI  = GND_P1
  4  S2  BI  = TDR_DIFF_100_BOT_DP
